(kicad_pcb
	(version 20260206)
	(generator "pcbnew")
	(generator_version "10.0")
	(general
		(thickness 1.6)
		(legacy_teardrops no)
	)
	(paper "A4")
	(title_block
		(title "04192023_DAF0TMB3IC0_F0TG_MB_C_brd_V02_OCP.brd")
		(comment 1 "Grand Teton / footprints 3170-3175 of 8354")
	)
	(layers
		(0 "F.Cu" signal "TOP")
		(4 "In1.Cu" signal "GND")
		(6 "In2.Cu" signal "IN1")
		(8 "In3.Cu" signal "GND1")
		(10 "In4.Cu" signal "IN2")
		(12 "In5.Cu" signal "GND2")
		(14 "In6.Cu" signal "IN3")
		(16 "In7.Cu" signal "GND3")
		(18 "In8.Cu" signal "VCC")
		(20 "In9.Cu" signal "VCC1")
		(22 "In10.Cu" signal "GND4")
		(24 "In11.Cu" signal "IN4")
		(26 "In12.Cu" signal "GND5")
		(28 "In13.Cu" signal "IN5")
		(30 "In14.Cu" signal "GND6")
		(32 "In15.Cu" signal "IN6")
		(34 "In16.Cu" signal "GND7")
		(2 "B.Cu" signal "BOTTOM")
		(9 "F.Adhes" user "F.Adhesive")
		(11 "B.Adhes" user "B.Adhesive")
		(13 "F.Paste" user "Package Geometry/Pastemask Top")
		(15 "B.Paste" user "Package Geometry/Pastemask Bottom")
		(5 "F.SilkS" user "Ref Des/Silkscreen Top")
		(7 "B.SilkS" user "Ref Des/Silkscreen Bottom")
		(1 "F.Mask" user "Board Geometry/Soldermask Top")
		(3 "B.Mask" user "Board Geometry/Soldermask Bottom")
		(17 "Dwgs.User" user "User.Drawings")
		(19 "Cmts.User" user "User.Comments")
		(21 "Eco1.User" user "User.Eco1")
		(23 "Eco2.User" user "User.Eco2")
		(25 "Edge.Cuts" user "Board Geometry/Outline")
		(27 "Margin" user)
		(31 "F.CrtYd" user "Package Geometry/Place Bound Top")
		(29 "B.CrtYd" user "Package Geometry/Place Bound Bottom")
		(35 "F.Fab" user "Ref Des/Assembly Top")
		(33 "B.Fab" user "Ref Des/Assembly Bottom")
	)
	(footprint ""
		(layer "F.Cu")
		(at 177.469546 -342.23198 90)
		(property "Reference" "PR395"
			(at 0 0 90)
			(layer "F.SilkS")
			(hide yes)
			(effects
				(font
					(size 1.27 1.27)
				)
			)
		)
		(property "Value" ""
			(at 0 0 90)
			(layer "F.Fab")
			(effects
				(font
					(size 1.27 1.27)
				)
			)
		)
		(duplicate_pad_numbers_are_jumpers no)
		(fp_line
			(start 0.7874 -0.4064)
			(end 0.7874 0.4064)
			(stroke
				(width 0.1524)
				(type default)
			)
			(layer "F.SilkS")
		)
		(fp_line
			(start -0.7874 -0.4064)
			(end 0.7874 -0.4064)
			(stroke
				(width 0.1524)
				(type default)
			)
			(layer "F.SilkS")
		)
		(fp_line
			(start 0.7874 0.4064)
			(end -0.7874 0.4064)
			(stroke
				(width 0.1524)
				(type default)
			)
			(layer "F.SilkS")
		)
		(fp_line
			(start -0.7874 0.4064)
			(end -0.7874 -0.4064)
			(stroke
				(width 0.1524)
				(type default)
			)
			(layer "F.SilkS")
		)
		(fp_line
			(start -0.12065 -0.305054)
			(end -0.12065 -0.2794)
			(stroke
				(width 0.1)
				(type default)
			)
			(layer "F.Fab")
		)
		(fp_line
			(start -0.67945 -0.305054)
			(end -0.12065 -0.305054)
			(stroke
				(width 0.1)
				(type default)
			)
			(layer "F.Fab")
		)
		(fp_line
			(start 0.67945 -0.3048)
			(end 0.67945 0.3048)
			(stroke
				(width 0.1)
				(type default)
			)
			(layer "F.Fab")
		)
		(fp_line
			(start 0.12065 -0.3048)
			(end 0.67945 -0.3048)
			(stroke
				(width 0.1)
				(type default)
			)
			(layer "F.Fab")
		)
		(fp_line
			(start 0.12065 -0.2794)
			(end 0.12065 -0.3048)
			(stroke
				(width 0.1)
				(type default)
			)
			(layer "F.Fab")
		)
		(fp_line
			(start -0.12065 -0.2794)
			(end 0.12065 -0.2794)
			(stroke
				(width 0.1)
				(type default)
			)
			(layer "F.Fab")
		)
		(fp_line
			(start 0.120396 0.2794)
			(end -0.12065 0.2794)
			(stroke
				(width 0.1)
				(type default)
			)
			(layer "F.Fab")
		)
		(fp_line
			(start -0.12065 0.2794)
			(end -0.12065 0.3048)
			(stroke
				(width 0.1)
				(type default)
			)
			(layer "F.Fab")
		)
		(fp_line
			(start 0.67945 0.3048)
			(end 0.120396 0.3048)
			(stroke
				(width 0.1)
				(type default)
			)
			(layer "F.Fab")
		)
		(fp_line
			(start 0.120396 0.3048)
			(end 0.120396 0.2794)
			(stroke
				(width 0.1)
				(type default)
			)
			(layer "F.Fab")
		)
		(fp_line
			(start -0.12065 0.3048)
			(end -0.67945 0.3048)
			(stroke
				(width 0.1)
				(type default)
			)
			(layer "F.Fab")
		)
		(fp_line
			(start -0.67945 0.3048)
			(end -0.67945 -0.305054)
			(stroke
				(width 0.1)
				(type default)
			)
			(layer "F.Fab")
		)
		(pad "1" smd circle
			(at -0.40005 0 90)
			(size 0 0)
			(layers "F.Cu" "F.Mask" "F.Paste")
			(net "PVDD11_S3_P1")
		)
		(pad "2" smd circle
			(at 0.40005 0 90)
			(size 0 0)
			(layers "F.Cu" "F.Mask" "F.Paste")
			(net "GND")
		)
	)
	(footprint ""
		(layer "F.Cu")
		(at 402.151088 -329.762612 180)
		(property "Reference" "R938"
			(at 0 0 180)
			(layer "F.SilkS")
			(hide yes)
			(effects
				(font
					(size 1.27 1.27)
				)
			)
		)
		(property "Value" ""
			(at 0 0 180)
			(layer "F.Fab")
			(effects
				(font
					(size 1.27 1.27)
				)
			)
		)
		(duplicate_pad_numbers_are_jumpers no)
		(fp_line
			(start 0.7874 0.4064)
			(end -0.7874 0.4064)
			(stroke
				(width 0.1524)
				(type default)
			)
			(layer "F.SilkS")
		)
		(fp_line
			(start 0.7874 -0.4064)
			(end 0.7874 0.4064)
			(stroke
				(width 0.1524)
				(type default)
			)
			(layer "F.SilkS")
		)
		(fp_line
			(start -0.7874 0.4064)
			(end -0.7874 -0.4064)
			(stroke
				(width 0.1524)
				(type default)
			)
			(layer "F.SilkS")
		)
		(fp_line
			(start -0.7874 -0.4064)
			(end 0.7874 -0.4064)
			(stroke
				(width 0.1524)
				(type default)
			)
			(layer "F.SilkS")
		)
		(fp_line
			(start 0.67945 0.3048)
			(end 0.120396 0.3048)
			(stroke
				(width 0.1)
				(type default)
			)
			(layer "F.Fab")
		)
		(fp_line
			(start 0.67945 -0.3048)
			(end 0.67945 0.3048)
			(stroke
				(width 0.1)
				(type default)
			)
			(layer "F.Fab")
		)
		(fp_line
			(start 0.12065 -0.2794)
			(end 0.12065 -0.3048)
			(stroke
				(width 0.1)
				(type default)
			)
			(layer "F.Fab")
		)
		(fp_line
			(start 0.12065 -0.3048)
			(end 0.67945 -0.3048)
			(stroke
				(width 0.1)
				(type default)
			)
			(layer "F.Fab")
		)
		(fp_line
			(start 0.120396 0.3048)
			(end 0.120396 0.2794)
			(stroke
				(width 0.1)
				(type default)
			)
			(layer "F.Fab")
		)
		(fp_line
			(start 0.120396 0.2794)
			(end -0.12065 0.2794)
			(stroke
				(width 0.1)
				(type default)
			)
			(layer "F.Fab")
		)
		(fp_line
			(start -0.12065 0.3048)
			(end -0.67945 0.3048)
			(stroke
				(width 0.1)
				(type default)
			)
			(layer "F.Fab")
		)
		(fp_line
			(start -0.12065 0.2794)
			(end -0.12065 0.3048)
			(stroke
				(width 0.1)
				(type default)
			)
			(layer "F.Fab")
		)
		(fp_line
			(start -0.12065 -0.2794)
			(end 0.12065 -0.2794)
			(stroke
				(width 0.1)
				(type default)
			)
			(layer "F.Fab")
		)
		(fp_line
			(start -0.12065 -0.305054)
			(end -0.12065 -0.2794)
			(stroke
				(width 0.1)
				(type default)
			)
			(layer "F.Fab")
		)
		(fp_line
			(start -0.67945 0.3048)
			(end -0.67945 -0.305054)
			(stroke
				(width 0.1)
				(type default)
			)
			(layer "F.Fab")
		)
		(fp_line
			(start -0.67945 -0.305054)
			(end -0.12065 -0.305054)
			(stroke
				(width 0.1)
				(type default)
			)
			(layer "F.Fab")
		)
		(pad "1" smd circle
			(at -0.40005 0 180)
			(size 0 0)
			(layers "F.Cu" "F.Mask" "F.Paste")
			(net "BOOT_RDY_H")
		)
		(pad "2" smd circle
			(at 0.40005 0 180)
			(size 0 0)
			(layers "F.Cu" "F.Mask" "F.Paste")
			(net "PVDD18_S5_P0")
		)
	)
	(footprint ""
		(layer "F.Cu")
		(at 73.96099 -177.625756 180)
		(property "Reference" "PU29"
			(at -0.44958 -6.724142 0)
			(unlocked yes)
			(layer "F.SilkS")
			(effects
				(font
					(size 0.7874 0.5842)
					(thickness 0.1524)
				)
				(justify left)
			)
		)
		(property "Value" ""
			(at 0 0 180)
			(layer "F.Fab")
			(effects
				(font
					(size 1.27 1.27)
				)
			)
		)
		(duplicate_pad_numbers_are_jumpers no)
		(fp_line
			(start 2.500122 2.999994)
			(end 2.2987 2.999994)
			(stroke
				(width 0.1524)
				(type default)
			)
			(layer "F.SilkS")
		)
		(fp_line
			(start 2.500122 2.339594)
			(end 2.500122 2.999994)
			(stroke
				(width 0.1524)
				(type default)
			)
			(layer "F.SilkS")
		)
		(fp_line
			(start 2.500122 -2.999994)
			(end 2.500122 -2.44348)
			(stroke
				(width 0.1524)
				(type default)
			)
			(layer "F.SilkS")
		)
		(fp_line
			(start 2.31394 -2.999994)
			(end 2.500122 -2.999994)
			(stroke
				(width 0.1524)
				(type default)
			)
			(layer "F.SilkS")
		)
		(fp_line
			(start -2.2987 2.999994)
			(end -2.500122 2.999994)
			(stroke
				(width 0.1524)
				(type default)
			)
			(layer "F.SilkS")
		)
		(fp_line
			(start -2.500122 2.999994)
			(end -2.500122 2.339594)
			(stroke
				(width 0.1524)
				(type default)
			)
			(layer "F.SilkS")
		)
		(fp_line
			(start -2.500122 0.6604)
			(end -2.500122 0.229108)
			(stroke
				(width 0.1524)
				(type default)
			)
			(layer "F.SilkS")
		)
		(fp_line
			(start -2.500122 -2.529078)
			(end -2.500122 -2.999994)
			(stroke
				(width 0.1524)
				(type default)
			)
			(layer "F.SilkS")
		)
		(fp_line
			(start -2.500122 -2.999994)
			(end -2.24409 -2.999994)
			(stroke
				(width 0.1524)
				(type default)
			)
			(layer "F.SilkS")
		)
		(fp_poly
			(pts
				(xy -2.765298 -2.452878) (xy -3.438652 -2.677414) (xy -2.989834 -3.126232)
			)
			(stroke
				(width 0)
				(type default)
			)
			(fill yes)
			(layer "F.SilkS")
		)
		(fp_line
			(start 2.500122 2.999994)
			(end -2.500122 2.999994)
			(stroke
				(width 0.1)
				(type default)
			)
			(layer "F.Fab")
		)
		(fp_line
			(start 2.500122 -2.999994)
			(end 2.500122 2.999994)
			(stroke
				(width 0.1)
				(type default)
			)
			(layer "F.Fab")
		)
		(fp_line
			(start -2.500122 2.999994)
			(end -2.500122 -2.999994)
			(stroke
				(width 0.1)
				(type default)
			)
			(layer "F.Fab")
		)
		(fp_line
			(start -2.500122 -2.999994)
			(end 2.500122 -2.999994)
			(stroke
				(width 0.1)
				(type default)
			)
			(layer "F.Fab")
		)
		(fp_poly
			(pts
				(xy -4.218432 -2.783078) (xy -4.218432 -1.767078) (xy -3.202432 -2.275078)
			)
			(stroke
				(width 0)
				(type default)
			)
			(fill yes)
			(layer "F.Fab")
		)
		(pad "1" smd rect
			(at -2.400046 -2.275078 270)
			(size 0.2286 0.6096)
			(layers "F.Cu" "F.Mask" "F.Paste")
			(net "PVDDCR_CPU0_P1_VOS5")
		)
		(pad "2" smd rect
			(at -2.400046 -1.82499 270)
			(size 0.2286 0.6096)
			(layers "F.Cu" "F.Mask" "F.Paste")
			(net "GND")
		)
		(pad "3" smd rect
			(at -2.400046 -1.374902 270)
			(size 0.2286 0.6096)
			(layers "F.Cu" "F.Mask" "F.Paste")
			(net "PVDDCR_CPU0_P1_VCC5")
		)
		(pad "4" smd rect
			(at -2.400046 -0.925068 270)
			(size 0.2286 0.6096)
			(layers "F.Cu" "F.Mask" "F.Paste")
			(net "PVDDCR_CPU0_P1_PVCC")
		)
		(pad "5" smd rect
			(at -2.400046 -0.47498 270)
			(size 0.2286 0.6096)
			(layers "F.Cu" "F.Mask" "F.Paste")
			(net "GND")
		)
		(pad "6" smd rect
			(at -2.400046 -0.024892 270)
			(size 0.2286 0.6096)
			(layers "F.Cu" "F.Mask" "F.Paste")
			(net "NC_PVDDCR_CPU0_P1_GL1_5")
		)
		(pad "7_9-20_24" smd circle
			(at 0 1.150112 270)
			(size 0 0)
			(layers "F.Cu" "F.Mask" "F.Paste")
			(net "GND")
		)
		(pad "10_19" smd rect
			(at 0 2.899918 270)
			(size 0.6096 4.318)
			(layers "F.Cu" "F.Mask" "F.Paste")
			(net "SW_PVDDCR_CPU0_P1_SW5")
		)
		(pad "25_29" smd rect
			(at 1.549908 -1.279906 90)
			(size 2.0574 2.3114)
			(layers "F.Cu" "F.Mask" "F.Paste")
			(net "SW_P12V_AUX_PVDDCR_CPU0_P1_FLT")
		)
		(pad "30" smd rect
			(at 2.05994 -2.899918 180)
			(size 0.2286 0.6096)
			(layers "F.Cu" "F.Mask" "F.Paste")
			(net "SW_P12V_AUX_PVDDCR_CPU0_P1_FLT")
		)
		(pad "31" smd rect
			(at 1.610106 -2.899918 180)
			(size 0.2286 0.6096)
			(layers "F.Cu" "F.Mask" "F.Paste")
			(net "NC_PVDDCR_CPU0_P1_DNC5")
		)
		(pad "32" smd rect
			(at 1.160018 -2.899918 180)
			(size 0.2286 0.6096)
			(layers "F.Cu" "F.Mask" "F.Paste")
			(net "SW_PVDDCR_CPU0_P1_PH5")
		)
		(pad "33" smd rect
			(at 0.70993 -2.899918 180)
			(size 0.2286 0.6096)
			(layers "F.Cu" "F.Mask" "F.Paste")
			(net "SW_PVDDCR_CPU0_P1_BOOT5")
		)
		(pad "34" smd rect
			(at 0.260096 -2.899918 180)
			(size 0.2286 0.6096)
			(layers "F.Cu" "F.Mask" "F.Paste")
			(net "PVDDCR_CPU0_P1_PWM5")
		)
		(pad "35" smd rect
			(at -0.189992 -2.899918 180)
			(size 0.2286 0.6096)
			(layers "F.Cu" "F.Mask" "F.Paste")
			(net "PVDDCR_CPU0_P1_VCC5")
		)
		(pad "36" smd rect
			(at -0.64008 -2.899918 180)
			(size 0.2286 0.6096)
			(layers "F.Cu" "F.Mask" "F.Paste")
			(net "PVDDCR_CPU0_P1_TEMP0")
		)
		(pad "37" smd rect
			(at -1.089914 -2.899918 180)
			(size 0.2286 0.6096)
			(layers "F.Cu" "F.Mask" "F.Paste")
			(net "PVDDCR_CPU0_P1_LSET5")
		)
		(pad "38" smd rect
			(at -1.540002 -2.899918 180)
			(size 0.2286 0.6096)
			(layers "F.Cu" "F.Mask" "F.Paste")
			(net "PVDDCR_CPU0_P1_IMON5")
		)
		(pad "39" smd rect
			(at -1.99009 -2.899918 180)
			(size 0.2286 0.6096)
			(layers "F.Cu" "F.Mask" "F.Paste")
			(net "PVDDCR_CPU0_P1_VCCS")
		)
		(pad "40" smd rect
			(at -0.87503 -1.27508 180)
			(size 1.7526 1.9558)
			(layers "F.Cu" "F.Mask" "F.Paste")
			(net "GND")
		)
		(pad "41" smd rect
			(at -1.525016 0.249936 90)
			(size 0.3048 0.4572)
			(layers "F.Cu" "F.Mask" "F.Paste")
			(net "NC_PVDDCR_CPU0_P1_GL2_5")
		)
		(zone
			(layer "F.Cu")
			(hatch none 0.5)
			(connect_pads
				(clearance 0)
			)
			(min_thickness 0.25)
			(keepout
				(tracks not_allowed)
				(vias allowed)
				(pads allowed)
				(copperpour not_allowed)
				(footprints allowed)
			)
			(placement
				(enabled no)
				(sheetname "")
			)
			(fill
				(thermal_gap 0.5)
				(thermal_bridge_width 0.5)
				(island_removal_mode 0)
			)
			(polygon
				(pts
					(xy 76.461112 -180.170074) (xy 76.461112 -179.87645) (xy 71.460868 -179.87645) (xy 71.460868 -180.170074)
					(xy 71.75119 -180.170074) (xy 76.17079 -180.170074)
				)
			)
		)
		(zone
			(layer "F.Cu")
			(hatch none 0.5)
			(connect_pads
				(clearance 0)
			)
			(min_thickness 0.25)
			(keepout
				(tracks not_allowed)
				(vias allowed)
				(pads allowed)
				(copperpour not_allowed)
				(footprints allowed)
			)
			(placement
				(enabled no)
				(sheetname "")
			)
			(fill
				(thermal_gap 0.5)
				(thermal_bridge_width 0.5)
				(island_removal_mode 0)
			)
			(polygon
				(pts
					(xy 73.90892 -177.37328) (xy 73.90892 -175.321976) (xy 75.76312 -175.321976) (xy 75.76312 -175.563022)
					(xy 76.005436 -175.563022) (xy 76.005436 -175.081438) (xy 72.126348 -175.081438) (xy 72.126348 -175.26635)
					(xy 73.617582 -175.26635) (xy 73.617582 -177.42535) (xy 71.460868 -177.42535) (xy 71.460868 -177.675032)
					(xy 73.607168 -177.675032)
				)
			)
		)
	)
	(footprint ""
		(layer "F.Cu")
		(at 358.384094 -325.310754 180)
		(property "Reference" "TP3"
			(at -0.90424 -0.772668 0)
			(unlocked yes)
			(layer "F.SilkS")
			(effects
				(font
					(size 0.7874 0.5842)
					(thickness 0.1524)
				)
				(justify left)
			)
		)
		(property "Value" ""
			(at 0 0 180)
			(layer "F.Fab")
			(effects
				(font
					(size 1.27 1.27)
				)
			)
		)
		(duplicate_pad_numbers_are_jumpers no)
		(pad "1" smd circle
			(at 0 0 180)
			(size 0.762 0.762)
			(layers "F.Cu" "F.Mask" "F.Paste")
			(net "VSENSE_VSS_SENSE_C_P0")
		)
	)
	(footprint ""
		(layer "F.Cu")
		(at 142.893542 -385.58216)
		(property "Reference" "R875"
			(at 0 0 0)
			(layer "F.SilkS")
			(hide yes)
			(effects
				(font
					(size 1.27 1.27)
				)
			)
		)
		(property "Value" ""
			(at 0 0 0)
			(layer "F.Fab")
			(effects
				(font
					(size 1.27 1.27)
				)
			)
		)
		(duplicate_pad_numbers_are_jumpers no)
		(fp_line
			(start -0.32512 -0.175006)
			(end 0.32512 -0.175006)
			(stroke
				(width 0.1)
				(type default)
			)
			(layer "F.Fab")
		)
		(fp_line
			(start -0.32512 0.175006)
			(end -0.32512 -0.175006)
			(stroke
				(width 0.1)
				(type default)
			)
			(layer "F.Fab")
		)
		(fp_line
			(start 0.32512 -0.175006)
			(end 0.32512 0.175006)
			(stroke
				(width 0.1)
				(type default)
			)
			(layer "F.Fab")
		)
		(fp_line
			(start 0.32512 0.175006)
			(end -0.32512 0.175006)
			(stroke
				(width 0.1)
				(type default)
			)
			(layer "F.Fab")
		)
		(pad "1" smd rect
			(at -0.2667 0)
			(size 0.3048 0.381)
			(layers "F.Cu" "F.Mask" "F.Paste")
			(net "GPIO2_RT_CPU1_P2")
		)
		(pad "2" smd rect
			(at 0.2667 0 180)
			(size 0.3048 0.381)
			(layers "F.Cu" "F.Mask" "F.Paste")
			(net "GND")
		)
	)
	(footprint ""
		(layer "F.Cu")
		(at 352.05543 -432.825652)
		(property "Reference" "R4549"
			(at 0 0 0)
			(layer "F.SilkS")
			(hide yes)
			(effects
				(font
					(size 1.27 1.27)
				)
			)
		)
		(property "Value" ""
			(at 0 0 0)
			(layer "F.Fab")
			(effects
				(font
					(size 1.27 1.27)
				)
			)
		)
		(duplicate_pad_numbers_are_jumpers no)
		(fp_line
			(start -0.7874 -0.4064)
			(end 0.7874 -0.4064)
			(stroke
				(width 0.1524)
				(type default)
			)
			(layer "F.SilkS")
		)
		(fp_line
			(start -0.7874 0.4064)
			(end -0.7874 -0.4064)
			(stroke
				(width 0.1524)
				(type default)
			)
			(layer "F.SilkS")
		)
		(fp_line
			(start 0.7874 -0.4064)
			(end 0.7874 0.4064)
			(stroke
				(width 0.1524)
				(type default)
			)
			(layer "F.SilkS")
		)
		(fp_line
			(start 0.7874 0.4064)
			(end -0.7874 0.4064)
			(stroke
				(width 0.1524)
				(type default)
			)
			(layer "F.SilkS")
		)
		(fp_line
			(start -0.67945 -0.305054)
			(end -0.12065 -0.305054)
			(stroke
				(width 0.1)
				(type default)
			)
			(layer "F.Fab")
		)
		(fp_line
			(start -0.67945 0.3048)
			(end -0.67945 -0.305054)
			(stroke
				(width 0.1)
				(type default)
			)
			(layer "F.Fab")
		)
		(fp_line
			(start -0.12065 -0.305054)
			(end -0.12065 -0.2794)
			(stroke
				(width 0.1)
				(type default)
			)
			(layer "F.Fab")
		)
		(fp_line
			(start -0.12065 -0.2794)
			(end 0.12065 -0.2794)
			(stroke
				(width 0.1)
				(type default)
			)
			(layer "F.Fab")
		)
		(fp_line
			(start -0.12065 0.2794)
			(end -0.12065 0.3048)
			(stroke
				(width 0.1)
				(type default)
			)
			(layer "F.Fab")
		)
		(fp_line
			(start -0.12065 0.3048)
			(end -0.67945 0.3048)
			(stroke
				(width 0.1)
				(type default)
			)
			(layer "F.Fab")
		)
		(fp_line
			(start 0.120396 0.2794)
			(end -0.12065 0.2794)
			(stroke
				(width 0.1)
				(type default)
			)
			(layer "F.Fab")
		)
		(fp_line
			(start 0.120396 0.3048)
			(end 0.120396 0.2794)
			(stroke
				(width 0.1)
				(type default)
			)
			(layer "F.Fab")
		)
		(fp_line
			(start 0.12065 -0.3048)
			(end 0.67945 -0.3048)
			(stroke
				(width 0.1)
				(type default)
			)
			(layer "F.Fab")
		)
		(fp_line
			(start 0.12065 -0.2794)
			(end 0.12065 -0.3048)
			(stroke
				(width 0.1)
				(type default)
			)
			(layer "F.Fab")
		)
		(fp_line
			(start 0.67945 -0.3048)
			(end 0.67945 0.3048)
			(stroke
				(width 0.1)
				(type default)
			)
			(layer "F.Fab")
		)
		(fp_line
			(start 0.67945 0.3048)
			(end 0.120396 0.3048)
			(stroke
				(width 0.1)
				(type default)
			)
			(layer "F.Fab")
		)
		(pad "1" smd circle
			(at -0.40005 0)
			(size 0 0)
			(layers "F.Cu" "F.Mask" "F.Paste")
			(net "P3V3_AUX")
		)
		(pad "2" smd circle
			(at 0.40005 0)
			(size 0 0)
			(layers "F.Cu" "F.Mask" "F.Paste")
			(net "SWB_HSC_EN_BUF_R")
		)
	)
)
